(kicad_pcb
	(version 20260206)
	(generator "pcbnew")
	(generator_version "10.0")
	(general
		(thickness 1.6)
		(legacy_teardrops no)
	)
	(paper "A4")
	(title_block
		(title "v2-pdb — ms_pdb_v2.brd")
		(comment 1 "Open CloudServer (Microsoft) / footprints 147-150 of 348")
	)
	(layers
		(0 "F.Cu" signal "TOP")
		(4 "In1.Cu" signal "GND")
		(6 "In2.Cu" signal "IN1")
		(8 "In3.Cu" signal "VCC")
		(10 "In4.Cu" signal "VCC1")
		(12 "In5.Cu" signal "IN2")
		(14 "In6.Cu" signal "GND1")
		(2 "B.Cu" signal "BOTTOM")
		(9 "F.Adhes" user "F.Adhesive")
		(11 "B.Adhes" user "B.Adhesive")
		(13 "F.Paste" user "Package Geometry/Pastemask Top")
		(15 "B.Paste" user "Package Geometry/Pastemask Bottom")
		(5 "F.SilkS" user "Ref Des/Silkscreen Top")
		(7 "B.SilkS" user "Ref Des/Silkscreen Bottom")
		(1 "F.Mask" user "Board Geometry/Soldermask Top")
		(3 "B.Mask" user "Board Geometry/Soldermask Bottom")
		(17 "Dwgs.User" user "User.Drawings")
		(19 "Cmts.User" user "User.Comments")
		(21 "Eco1.User" user "User.Eco1")
		(23 "Eco2.User" user "User.Eco2")
		(25 "Edge.Cuts" user "Board Geometry/Outline")
		(27 "Margin" user)
		(31 "F.CrtYd" user "Package Geometry/Place Bound Top")
		(29 "B.CrtYd" user "Package Geometry/Place Bound Bottom")
		(35 "F.Fab" user "Ref Des/Assembly Top")
		(33 "B.Fab" user "Ref Des/Assembly Bottom")
	)
	(footprint ""
		(layer "F.Cu")
		(at 50.217578 -84.273644 180)
		(property "Reference" "CE4"
			(at 1.809242 -5.224018 0)
			(unlocked yes)
			(layer "F.SilkS")
			(effects
				(font
					(size 0.7874 0.5842)
					(thickness 0.1524)
				)
				(justify left)
			)
		)
		(property "Value" ""
			(at 0 0 180)
			(layer "F.Fab")
			(effects
				(font
					(size 1.27 1.27)
				)
			)
		)
		(duplicate_pad_numbers_are_jumpers no)
		(fp_line
			(start 0 -4.2672)
			(end 0 4.2672)
			(stroke
				(width 0.1524)
				(type default)
			)
			(layer "F.SilkS")
		)
		(fp_circle
			(center 0 0)
			(end -4.2672 0)
			(stroke
				(width 0.1524)
				(type default)
			)
			(fill no)
			(layer "F.SilkS")
		)
		(fp_poly
			(pts
				(arc
					(start 0 -4.2672)
					(mid 4.2672 0)
					(end 0 4.2672)
				)
			)
			(stroke
				(width 0)
				(type default)
			)
			(fill yes)
			(layer "F.SilkS")
		)
		(fp_poly
			(pts
				(xy -2.5146 -0.762) (xy -0.9906 -0.762) (xy -0.9906 0.762) (xy -2.5146 0.762)
			)
			(stroke
				(width 0)
				(type default)
			)
			(fill no)
			(layer "B.CrtYd")
		)
		(fp_poly
			(pts
				(arc
					(start 1.7526 0.762)
					(mid 2.291415 -0.538815)
					(end 0.9906 0)
				)
				(arc
					(start 0.9906 0.0254)
					(mid 1.206345 0.546255)
					(end 1.7272 0.762)
				)
			)
			(stroke
				(width 0)
				(type default)
			)
			(fill no)
			(layer "B.CrtYd")
		)
		(fp_poly
			(pts
				(arc
					(start -4.2672 0)
					(mid 4.2672 0)
					(end -4.2672 0)
				)
			)
			(stroke
				(width 0)
				(type default)
			)
			(fill no)
			(layer "F.CrtYd")
		)
		(fp_circle
			(center 0 0)
			(end -4.2672 0)
			(stroke
				(width 0.1)
				(type default)
			)
			(fill no)
			(layer "F.Fab")
		)
		(fp_text user "+"
			(at -3.604514 -4.129786 180)
			(unlocked yes)
			(layer "F.SilkS")
			(effects
				(font
					(size 1.905 1.4224)
					(thickness 0.1524)
				)
				(justify left)
			)
		)
		(fp_text user "+"
			(at -5.6642 -0.34925 180)
			(unlocked yes)
			(layer "F.Fab")
			(effects
				(font
					(size 1.905 1.4224)
					(thickness 0.000001)
				)
				(justify left)
			)
		)
		(pad "1" thru_hole rect
			(at -1.75006 0 180)
			(size 1.397 1.397)
			(drill 0.9144)
			(layers "*.Cu" "*.Mask")
			(remove_unused_layers no)
			(net "P12V")
			(clearance 0.0127)
			(thermal_gap 0.0127)
			(padstack
				(mode front_inner_back)
				(layer "Inner"
					(shape circle)
					(size 1.397 1.397)
					(clearance 0.0127)
				)
				(layer "B.Cu"
					(shape rect)
					(size 1.397 1.397)
					(clearance 0.0127)
				)
			)
		)
		(pad "2" thru_hole circle
			(at 1.75006 0 180)
			(size 1.397 1.397)
			(drill 0.9144)
			(layers "*.Cu" "*.Mask")
			(remove_unused_layers no)
			(net "GND")
			(clearance 0.0127)
			(thermal_gap 0.0127)
		)
	)
	(footprint ""
		(layer "F.Cu")
		(at 25.874472 -367.771426 180)
		(property "Reference" "R53"
			(at 3.856228 0.385064 0)
			(unlocked yes)
			(layer "F.SilkS")
			(effects
				(font
					(size 0.7874 0.5842)
					(thickness 0.1524)
				)
				(justify left)
			)
		)
		(property "Value" ""
			(at 0 0 180)
			(layer "F.Fab")
			(effects
				(font
					(size 1.27 1.27)
				)
			)
		)
		(duplicate_pad_numbers_are_jumpers no)
		(fp_line
			(start 0.7874 0.4064)
			(end -0.7874 0.4064)
			(stroke
				(width 0.1524)
				(type default)
			)
			(layer "F.SilkS")
		)
		(fp_line
			(start 0.7874 -0.4064)
			(end 0.7874 0.4064)
			(stroke
				(width 0.1524)
				(type default)
			)
			(layer "F.SilkS")
		)
		(fp_line
			(start -0.7874 0.4064)
			(end -0.7874 -0.4064)
			(stroke
				(width 0.1524)
				(type default)
			)
			(layer "F.SilkS")
		)
		(fp_line
			(start -0.7874 -0.4064)
			(end 0.7874 -0.4064)
			(stroke
				(width 0.1524)
				(type default)
			)
			(layer "F.SilkS")
		)
		(fp_poly
			(pts
				(xy -0.508 0.2794) (xy -0.508 0.2286) (xy -0.635 0.2286) (xy -0.635 -0.254) (xy -0.5334 -0.254)
				(xy -0.5334 -0.2794) (xy 0.5334 -0.2794) (xy 0.5334 -0.254) (xy 0.635 -0.254) (xy 0.635 0.254) (xy 0.5334 0.254)
				(xy 0.5334 0.2794)
			)
			(stroke
				(width 0)
				(type default)
			)
			(fill no)
			(layer "F.CrtYd")
		)
		(pad "1" smd rect
			(at 0.40005 0 180)
			(size 0.4572 0.508)
			(layers "F.Cu" "F.Mask" "F.Paste")
			(net "GND")
		)
		(pad "2" smd rect
			(at -0.40005 0 180)
			(size 0.4572 0.508)
			(layers "F.Cu" "F.Mask" "F.Paste")
			(net "PSU5_PS_ON_N")
		)
	)
	(footprint ""
		(layer "F.Cu")
		(at 11.444224 -461.694022)
		(property "Reference" "J20"
			(at -5.522214 -4.48056 0)
			(unlocked yes)
			(layer "F.SilkS")
			(effects
				(font
					(size 0.7874 0.5842)
					(thickness 0.1524)
				)
				(justify left)
			)
		)
		(property "Value" ""
			(at 0 0 0)
			(layer "F.Fab")
			(effects
				(font
					(size 1.27 1.27)
				)
			)
		)
		(duplicate_pad_numbers_are_jumpers no)
		(fp_line
			(start -8.949944 17.100042)
			(end -8.949944 20.699984)
			(stroke
				(width 0.1524)
				(type default)
			)
			(layer "F.SilkS")
		)
		(fp_line
			(start -8.949944 20.699984)
			(end -7.349998 20.699984)
			(stroke
				(width 0.1524)
				(type default)
			)
			(layer "F.SilkS")
		)
		(fp_line
			(start -7.349998 -3.299968)
			(end 2.450084 -3.299968)
			(stroke
				(width 0.1524)
				(type default)
			)
			(layer "F.SilkS")
		)
		(fp_line
			(start -7.349998 -2.899918)
			(end 2.450084 -2.899918)
			(stroke
				(width 0.1524)
				(type default)
			)
			(layer "F.SilkS")
		)
		(fp_line
			(start -7.349998 17.100042)
			(end -8.949944 17.100042)
			(stroke
				(width 0.1524)
				(type default)
			)
			(layer "F.SilkS")
		)
		(fp_line
			(start -7.349998 40.699944)
			(end -7.349998 -3.299968)
			(stroke
				(width 0.1524)
				(type default)
			)
			(layer "F.SilkS")
		)
		(fp_line
			(start -7.349998 41.099994)
			(end -7.349998 40.699944)
			(stroke
				(width 0.1524)
				(type default)
			)
			(layer "F.SilkS")
		)
		(fp_line
			(start 2.450084 -3.299968)
			(end 2.450084 -2.899918)
			(stroke
				(width 0.1524)
				(type default)
			)
			(layer "F.SilkS")
		)
		(fp_line
			(start 2.450084 -2.899918)
			(end 2.450084 40.699944)
			(stroke
				(width 0.1524)
				(type default)
			)
			(layer "F.SilkS")
		)
		(fp_line
			(start 2.450084 40.699944)
			(end -7.349998 40.699944)
			(stroke
				(width 0.1524)
				(type default)
			)
			(layer "F.SilkS")
		)
		(fp_line
			(start 2.450084 40.699944)
			(end 2.450084 41.099994)
			(stroke
				(width 0.1524)
				(type default)
			)
			(layer "F.SilkS")
		)
		(fp_line
			(start 2.450084 41.099994)
			(end -7.349998 41.099994)
			(stroke
				(width 0.1524)
				(type default)
			)
			(layer "F.SilkS")
		)
		(fp_poly
			(pts
				(xy 0.042418 -5.091176) (xy -1.227582 -5.091176) (xy -0.567182 -3.567176)
			)
			(stroke
				(width 0)
				(type default)
			)
			(fill yes)
			(layer "F.SilkS")
		)
		(fp_poly
			(pts
				(xy -7.349998 17.100042) (xy -8.949944 17.100042) (xy -8.949944 20.699984) (xy -7.349998 20.699984)
			)
			(stroke
				(width 0)
				(type default)
			)
			(fill yes)
			(layer "F.SilkS")
		)
		(fp_poly
			(pts
				(xy 1.0414 -1.0414) (xy -6.5278 -1.0414) (xy -6.5532 -1.0414) (xy -6.5532 38.8366) (xy -6.5278 38.8366)
				(xy 1.0414 38.8366)
			)
			(stroke
				(width 0)
				(type default)
			)
			(fill no)
			(layer "B.CrtYd")
		)
		(fp_poly
			(pts
				(xy -8.949944 17.100042) (xy -7.349998 17.100042) (xy -7.349998 -3.299968) (xy 2.450084 -3.299968)
				(xy 2.450084 41.099994) (xy -7.349998 41.099994) (xy -7.349998 20.699984) (xy -8.949944 20.699984)
			)
			(stroke
				(width 0)
				(type default)
			)
			(fill no)
			(layer "F.CrtYd")
		)
		(fp_line
			(start -8.949944 17.100042)
			(end -8.949944 20.699984)
			(stroke
				(width 0.1)
				(type default)
			)
			(layer "F.Fab")
		)
		(fp_line
			(start -8.949944 20.699984)
			(end -7.349998 20.699984)
			(stroke
				(width 0.1)
				(type default)
			)
			(layer "F.Fab")
		)
		(fp_line
			(start -7.349998 -3.299968)
			(end 2.450084 -3.299968)
			(stroke
				(width 0.1)
				(type default)
			)
			(layer "F.Fab")
		)
		(fp_line
			(start -7.349998 -2.899918)
			(end -7.349998 -3.299968)
			(stroke
				(width 0.1)
				(type default)
			)
			(layer "F.Fab")
		)
		(fp_line
			(start -7.349998 -2.899918)
			(end 2.44983 -2.899918)
			(stroke
				(width 0.1)
				(type default)
			)
			(layer "F.Fab")
		)
		(fp_line
			(start -7.349998 17.100042)
			(end -8.949944 17.100042)
			(stroke
				(width 0.1)
				(type default)
			)
			(layer "F.Fab")
		)
		(fp_line
			(start -7.349998 40.699944)
			(end -7.349998 -2.899918)
			(stroke
				(width 0.1)
				(type default)
			)
			(layer "F.Fab")
		)
		(fp_line
			(start -7.349998 41.099994)
			(end -7.349998 40.699944)
			(stroke
				(width 0.1)
				(type default)
			)
			(layer "F.Fab")
		)
		(fp_line
			(start 2.44983 -2.899918)
			(end 2.44983 40.699944)
			(stroke
				(width 0.1)
				(type default)
			)
			(layer "F.Fab")
		)
		(fp_line
			(start 2.44983 40.699944)
			(end -7.349998 40.699944)
			(stroke
				(width 0.1)
				(type default)
			)
			(layer "F.Fab")
		)
		(fp_line
			(start 2.450084 -3.299968)
			(end 2.450084 -2.899918)
			(stroke
				(width 0.1)
				(type default)
			)
			(layer "F.Fab")
		)
		(fp_line
			(start 2.450084 40.699944)
			(end 2.450084 41.099994)
			(stroke
				(width 0.1)
				(type default)
			)
			(layer "F.Fab")
		)
		(fp_line
			(start 2.450084 41.099994)
			(end -7.349998 41.099994)
			(stroke
				(width 0.1)
				(type default)
			)
			(layer "F.Fab")
		)
		(fp_poly
			(pts
				(xy 0.409956 -4.940808) (xy -0.860044 -4.940808) (xy -0.199644 -3.416808)
			)
			(stroke
				(width 0)
				(type default)
			)
			(fill yes)
			(layer "F.Fab")
		)
		(fp_text user "11"
			(at -9.198356 -0.33655 0)
			(unlocked yes)
			(layer "F.SilkS")
			(effects
				(font
					(size 0.7874 0.5842)
					(thickness 0.1524)
				)
				(justify left)
			)
		)
		(fp_text user "20"
			(at -6.240526 42.137076 0)
			(unlocked yes)
			(layer "F.SilkS")
			(effects
				(font
					(size 0.7874 0.5842)
					(thickness 0.1524)
				)
				(justify left)
			)
		)
		(fp_text user "1"
			(at -1.67767 -4.278122 0)
			(unlocked yes)
			(layer "F.SilkS")
			(effects
				(font
					(size 0.7874 0.5842)
					(thickness 0.1524)
				)
				(justify left)
			)
		)
		(fp_text user "10"
			(at -0.358902 42.337482 0)
			(unlocked yes)
			(layer "F.SilkS")
			(effects
				(font
					(size 0.7874 0.5842)
					(thickness 0.1524)
				)
				(justify left)
			)
		)
		(fp_text user "11"
			(at -7.229856 -2.581656 90)
			(unlocked yes)
			(layer "B.SilkS")
			(effects
				(font
					(size 0.7874 0.5842)
					(thickness 0.1524)
				)
				(justify left mirror)
			)
		)
		(fp_text user "20"
			(at -5.506212 40.406574 270)
			(unlocked yes)
			(layer "B.SilkS")
			(effects
				(font
					(size 0.7874 0.5842)
					(thickness 0.1524)
				)
				(justify left mirror)
			)
		)
		(fp_text user "1"
			(at -0.316738 -2.194306 90)
			(unlocked yes)
			(layer "B.SilkS")
			(effects
				(font
					(size 0.7874 0.5842)
					(thickness 0.1524)
				)
				(justify left mirror)
			)
		)
		(fp_text user "10"
			(at -0.15875 40.350948 270)
			(unlocked yes)
			(layer "B.SilkS")
			(effects
				(font
					(size 0.7874 0.5842)
					(thickness 0.1524)
				)
				(justify left mirror)
			)
		)
		(fp_text user "11"
			(at -5.506212 -1.086612 270)
			(unlocked yes)
			(layer "B.Fab")
			(effects
				(font
					(size 0.7874 0.5842)
					(thickness 0.000001)
				)
				(justify left mirror)
			)
		)
		(fp_text user "20"
			(at -5.506212 40.406574 270)
			(unlocked yes)
			(layer "B.Fab")
			(effects
				(font
					(size 0.7874 0.5842)
					(thickness 0.000001)
				)
				(justify left mirror)
			)
		)
		(fp_text user "10"
			(at -0.15875 40.350948 270)
			(unlocked yes)
			(layer "B.Fab")
			(effects
				(font
					(size 0.7874 0.5842)
					(thickness 0.000001)
				)
				(justify left mirror)
			)
		)
		(fp_text user "1"
			(at 0.01905 -1.112012 270)
			(unlocked yes)
			(layer "B.Fab")
			(effects
				(font
					(size 0.7874 0.5842)
					(thickness 0.000001)
				)
				(justify left mirror)
			)
		)
		(fp_text user "20"
			(at -5.506212 41.264332 270)
			(unlocked yes)
			(layer "F.Fab")
			(effects
				(font
					(size 0.7874 0.5842)
					(thickness 0.000001)
				)
				(justify left)
			)
		)
		(fp_text user "11"
			(at -5.455412 -4.713224 270)
			(unlocked yes)
			(layer "F.Fab")
			(effects
				(font
					(size 0.7874 0.5842)
					(thickness 0.000001)
				)
				(justify left)
			)
		)
		(fp_text user "10"
			(at -0.183896 41.102534 270)
			(unlocked yes)
			(layer "F.Fab")
			(effects
				(font
					(size 0.7874 0.5842)
					(thickness 0.000001)
				)
				(justify left)
			)
		)
		(fp_text user "1"
			(at 0.53086 -3.95732 270)
			(unlocked yes)
			(layer "F.Fab")
			(effects
				(font
					(size 0.7874 0.5842)
					(thickness 0.000001)
				)
				(justify left)
			)
		)
		(pad "1" thru_hole rect
			(at 0 0 270)
			(size 1.9558 1.9558)
			(drill 1.4478)
			(layers "*.Cu" "*.Mask")
			(remove_unused_layers no)
			(net "FAN1_TACH")
			(clearance 0)
			(padstack
				(mode front_inner_back)
				(layer "Inner"
					(shape circle)
					(size 1.9558 1.9558)
					(clearance 0)
				)
				(layer "B.Cu"
					(shape rect)
					(size 1.9558 1.9558)
					(clearance 0)
				)
			)
		)
		(pad "2" thru_hole circle
			(at 0 4.19989 270)
			(size 1.9558 1.9558)
			(drill 1.4478)
			(layers "*.Cu" "*.Mask")
			(remove_unused_layers no)
			(net "P12V")
			(clearance 0)
		)
		(pad "3" thru_hole circle
			(at 0 8.400034 270)
			(size 1.9558 1.9558)
			(drill 1.4478)
			(layers "*.Cu" "*.Mask")
			(remove_unused_layers no)
			(net "P12V")
			(clearance 0)
		)
		(pad "4" thru_hole circle
			(at 0 12.599924 270)
			(size 1.9558 1.9558)
			(drill 1.4478)
			(layers "*.Cu" "*.Mask")
			(remove_unused_layers no)
			(net "FAN2_TACH")
			(clearance 0)
		)
		(pad "5" thru_hole circle
			(at 0 16.800068 270)
			(size 1.9558 1.9558)
			(drill 1.4478)
			(layers "*.Cu" "*.Mask")
			(remove_unused_layers no)
			(net "P12V")
			(clearance 0)
		)
		(pad "6" thru_hole circle
			(at 0 20.999958 270)
			(size 1.9558 1.9558)
			(drill 1.4478)
			(layers "*.Cu" "*.Mask")
			(remove_unused_layers no)
			(net "P12V")
			(clearance 0)
		)
		(pad "7" thru_hole circle
			(at 0 25.200102 270)
			(size 1.9558 1.9558)
			(drill 1.4478)
			(layers "*.Cu" "*.Mask")
			(remove_unused_layers no)
			(net "FAN3_TACH")
			(clearance 0)
		)
		(pad "8" thru_hole circle
			(at 0 29.399992 270)
			(size 1.9558 1.9558)
			(drill 1.4478)
			(layers "*.Cu" "*.Mask")
			(remove_unused_layers no)
			(net "P12V")
			(clearance 0)
		)
		(pad "9" thru_hole circle
			(at 0 33.599882 270)
			(size 1.9558 1.9558)
			(drill 1.4478)
			(layers "*.Cu" "*.Mask")
			(remove_unused_layers no)
			(net "P12V")
			(clearance 0)
		)
		(pad "10" thru_hole circle
			(at 0 37.800026 270)
			(size 1.9558 1.9558)
			(drill 1.4478)
			(layers "*.Cu" "*.Mask")
			(remove_unused_layers no)
			(net "FAN4_TACH")
			(clearance 0)
		)
		(pad "11" thru_hole circle
			(at -5.500116 0 270)
			(size 1.9558 1.9558)
			(drill 1.4478)
			(layers "*.Cu" "*.Mask")
			(remove_unused_layers no)
			(net "FAN5_TACH")
			(clearance 0)
		)
		(pad "12" thru_hole circle
			(at -5.500116 4.19989 270)
			(size 1.9558 1.9558)
			(drill 1.4478)
			(layers "*.Cu" "*.Mask")
			(remove_unused_layers no)
			(net "GND")
			(clearance 0)
		)
		(pad "13" thru_hole circle
			(at -5.500116 8.400034 270)
			(size 1.9558 1.9558)
			(drill 1.4478)
			(layers "*.Cu" "*.Mask")
			(remove_unused_layers no)
			(net "GND")
			(clearance 0)
		)
		(pad "14" thru_hole circle
			(at -5.500116 12.599924 270)
			(size 1.9558 1.9558)
			(drill 1.4478)
			(layers "*.Cu" "*.Mask")
			(remove_unused_layers no)
			(net "FAN6_TACH")
			(clearance 0)
		)
		(pad "15" thru_hole circle
			(at -5.500116 16.800068 270)
			(size 1.9558 1.9558)
			(drill 1.4478)
			(layers "*.Cu" "*.Mask")
			(remove_unused_layers no)
			(net "GND")
			(clearance 0)
		)
		(pad "16" thru_hole circle
			(at -5.500116 20.999958 270)
			(size 1.9558 1.9558)
			(drill 1.4478)
			(layers "*.Cu" "*.Mask")
			(remove_unused_layers no)
			(net "GND")
			(clearance 0)
		)
		(pad "17" thru_hole circle
			(at -5.500116 25.200102 270)
			(size 1.9558 1.9558)
			(drill 1.4478)
			(layers "*.Cu" "*.Mask")
			(remove_unused_layers no)
			(net "FAN_PWM")
			(clearance 0)
		)
		(pad "18" thru_hole circle
			(at -5.500116 29.399992 270)
			(size 1.9558 1.9558)
			(drill 1.4478)
			(layers "*.Cu" "*.Mask")
			(remove_unused_layers no)
			(net "GND")
			(clearance 0)
		)
		(pad "19" thru_hole circle
			(at -5.500116 33.599882 270)
			(size 1.9558 1.9558)
			(drill 1.4478)
			(layers "*.Cu" "*.Mask")
			(remove_unused_layers no)
			(net "GND")
			(clearance 0)
		)
		(pad "20" thru_hole circle
			(at -5.500116 37.800026 270)
			(size 1.9558 1.9558)
			(drill 1.4478)
			(layers "*.Cu" "*.Mask")
			(remove_unused_layers no)
			(net "FAN_PWM")
			(clearance 0)
		)
	)
	(footprint ""
		(layer "F.Cu")
		(at 68.607686 -172.135546 90)
		(property "Reference" "C35"
			(at -4.082034 0.060706 90)
			(unlocked yes)
			(layer "F.SilkS")
			(effects
				(font
					(size 0.7874 0.5842)
					(thickness 0.1524)
				)
				(justify left)
			)
		)
		(property "Value" ""
			(at 0 0 90)
			(layer "F.Fab")
			(effects
				(font
					(size 1.27 1.27)
				)
			)
		)
		(duplicate_pad_numbers_are_jumpers no)
		(fp_line
			(start 0.7874 -0.4064)
			(end 0.7874 0.4064)
			(stroke
				(width 0.1524)
				(type default)
			)
			(layer "F.SilkS")
		)
		(fp_line
			(start -0.7874 -0.4064)
			(end 0.7874 -0.4064)
			(stroke
				(width 0.1524)
				(type default)
			)
			(layer "F.SilkS")
		)
		(fp_line
			(start 0 0.381)
			(end 0 -0.381)
			(stroke
				(width 0.1524)
				(type default)
			)
			(layer "F.SilkS")
		)
		(fp_line
			(start 0.7874 0.4064)
			(end -0.7874 0.4064)
			(stroke
				(width 0.1524)
				(type default)
			)
			(layer "F.SilkS")
		)
		(fp_line
			(start -0.7874 0.4064)
			(end -0.7874 -0.4064)
			(stroke
				(width 0.1524)
				(type default)
			)
			(layer "F.SilkS")
		)
		(fp_poly
			(pts
				(xy -0.5334 0.254) (xy -0.635 0.254) (xy -0.635 0.2286) (xy -0.635 -0.254) (xy -0.5334 -0.254) (xy -0.5334 -0.2794)
				(xy 0.5334 -0.2794) (xy 0.5334 -0.254) (xy 0.635 -0.254) (xy 0.635 0.254) (xy 0.5334 0.254) (xy 0.5334 0.2794)
				(xy -0.508 0.2794) (xy -0.5334 0.2794)
			)
			(stroke
				(width 0)
				(type default)
			)
			(fill no)
			(layer "F.CrtYd")
		)
		(pad "1" smd rect
			(at 0.40005 0 90)
			(size 0.4572 0.508)
			(layers "F.Cu" "F.Mask" "F.Paste")
			(net "P12V")
		)
		(pad "2" smd rect
			(at -0.40005 0 90)
			(size 0.4572 0.508)
			(layers "F.Cu" "F.Mask" "F.Paste")
			(net "GND")
		)
	)
)
